# T6G (Grand Teton) — schematic netlist excerpt (pin names and nets, part order shuffled) for the footprints in the layout excerpt that follows; sources: Cadence DE-HDL packaged netlist, KiCad conversion of 04192023_DAF0TMB3IC0_F0TG_MB_C_brd_V02_OCP.brd

C2595  Q_CAP  22UF 4V 20% X6S  pkg C0402  page 70 : A = PVDDCR_SOC_P0 ; B = GND
R808  Q_RES  0 5% CHIP  pkg 0201LF  page 185 : A = SMB_RT_CPU1_P2_ROM_MUX_2D_SDA ; B = SMB_RT_CPU1_P2_ROM_MUX_2D_R_SDA
PC471  Q_CAP  1UF 16V 10% X6S  pkg C0402  page 193 : A = PVDDCR_CPU0_P0_VCC ; B = GND

(kicad_pcb
	(version 20260206)
	(generator "pcbnew")
	(generator_version "10.0")
	(general
		(thickness 1.6)
		(legacy_teardrops no)
	)
	(paper "A4")
	(title_block
		(title "04192023_DAF0TMB3IC0_F0TG_MB_C_brd_V02_OCP.brd")
		(comment 1 "Grand Teton / footprints 7429-7431 of 8354")
	)
	(layers
		(0 "F.Cu" signal "TOP")
		(4 "In1.Cu" signal "GND")
		(6 "In2.Cu" signal "IN1")
		(8 "In3.Cu" signal "GND1")
		(10 "In4.Cu" signal "IN2")
		(12 "In5.Cu" signal "GND2")
		(14 "In6.Cu" signal "IN3")
		(16 "In7.Cu" signal "GND3")
		(18 "In8.Cu" signal "VCC")
		(20 "In9.Cu" signal "VCC1")
		(22 "In10.Cu" signal "GND4")
		(24 "In11.Cu" signal "IN4")
		(26 "In12.Cu" signal "GND5")
		(28 "In13.Cu" signal "IN5")
		(30 "In14.Cu" signal "GND6")
		(32 "In15.Cu" signal "IN6")
		(34 "In16.Cu" signal "GND7")
		(2 "B.Cu" signal "BOTTOM")
		(9 "F.Adhes" user "F.Adhesive")
		(11 "B.Adhes" user "B.Adhesive")
		(13 "F.Paste" user "Package Geometry/Pastemask Top")
		(15 "B.Paste" user "Package Geometry/Pastemask Bottom")
		(5 "F.SilkS" user "Ref Des/Silkscreen Top")
		(7 "B.SilkS" user "Ref Des/Silkscreen Bottom")
		(1 "F.Mask" user "Board Geometry/Soldermask Top")
		(3 "B.Mask" user "Board Geometry/Soldermask Bottom")
		(17 "Dwgs.User" user "User.Drawings")
		(19 "Cmts.User" user "User.Comments")
		(21 "Eco1.User" user "User.Eco1")
		(23 "Eco2.User" user "User.Eco2")
		(25 "Edge.Cuts" user "Board Geometry/Outline")
		(27 "Margin" user)
		(31 "F.CrtYd" user "Package Geometry/Place Bound Top")
		(29 "B.CrtYd" user "Package Geometry/Place Bound Bottom")
		(35 "F.Fab" user "Ref Des/Assembly Top")
		(33 "B.Fab" user "Ref Des/Assembly Bottom")
	)
	(footprint ""
		(layer "B.Cu")
		(at 359.740454 -251.40031 180)
		(property "Reference" "C2595"
			(at 0 0 0)
			(layer "B.SilkS")
			(hide yes)
			(effects
				(font
					(size 1.27 1.27)
				)
				(justify mirror)
			)
		)
		(property "Value" ""
			(at 0 0 0)
			(layer "B.Fab")
			(effects
				(font
					(size 1.27 1.27)
				)
				(justify mirror)
			)
		)
		(duplicate_pad_numbers_are_jumpers no)
		(fp_line
			(start 0.7874 0.4064)
			(end 0.7874 -0.4064)
			(stroke
				(width 0.1524)
				(type default)
			)
			(layer "B.SilkS")
		)
		(fp_line
			(start 0.7874 -0.4064)
			(end -0.7874 -0.4064)
			(stroke
				(width 0.1524)
				(type default)
			)
			(layer "B.SilkS")
		)
		(fp_line
			(start -0.7874 0.4064)
			(end 0.7874 0.4064)
			(stroke
				(width 0.1524)
				(type default)
			)
			(layer "B.SilkS")
		)
		(fp_line
			(start -0.7874 -0.4064)
			(end -0.7874 0.4064)
			(stroke
				(width 0.1524)
				(type default)
			)
			(layer "B.SilkS")
		)
		(fp_line
			(start 0.67945 0.3048)
			(end 0.67945 -0.305054)
			(stroke
				(width 0.1)
				(type default)
			)
			(layer "B.Fab")
		)
		(fp_line
			(start 0.67945 -0.305054)
			(end 0.12065 -0.305054)
			(stroke
				(width 0.1)
				(type default)
			)
			(layer "B.Fab")
		)
		(fp_line
			(start 0.12065 0.3048)
			(end 0.67945 0.3048)
			(stroke
				(width 0.1)
				(type default)
			)
			(layer "B.Fab")
		)
		(fp_line
			(start 0.12065 0.2794)
			(end 0.12065 0.3048)
			(stroke
				(width 0.1)
				(type default)
			)
			(layer "B.Fab")
		)
		(fp_line
			(start 0.12065 -0.2794)
			(end -0.12065 -0.2794)
			(stroke
				(width 0.1)
				(type default)
			)
			(layer "B.Fab")
		)
		(fp_line
			(start 0.12065 -0.305054)
			(end 0.12065 -0.2794)
			(stroke
				(width 0.1)
				(type default)
			)
			(layer "B.Fab")
		)
		(fp_line
			(start -0.120396 0.3048)
			(end -0.120396 0.2794)
			(stroke
				(width 0.1)
				(type default)
			)
			(layer "B.Fab")
		)
		(fp_line
			(start -0.120396 0.2794)
			(end 0.12065 0.2794)
			(stroke
				(width 0.1)
				(type default)
			)
			(layer "B.Fab")
		)
		(fp_line
			(start -0.12065 -0.2794)
			(end -0.12065 -0.3048)
			(stroke
				(width 0.1)
				(type default)
			)
			(layer "B.Fab")
		)
		(fp_line
			(start -0.12065 -0.3048)
			(end -0.67945 -0.3048)
			(stroke
				(width 0.1)
				(type default)
			)
			(layer "B.Fab")
		)
		(fp_line
			(start -0.67945 0.3048)
			(end -0.120396 0.3048)
			(stroke
				(width 0.1)
				(type default)
			)
			(layer "B.Fab")
		)
		(fp_line
			(start -0.67945 -0.3048)
			(end -0.67945 0.3048)
			(stroke
				(width 0.1)
				(type default)
			)
			(layer "B.Fab")
		)
		(pad "1" smd circle
			(at 0.40005 0)
			(size 0 0)
			(layers "B.Cu" "B.Mask" "B.Paste")
			(net "PVDDCR_SOC_P0")
		)
		(pad "2" smd circle
			(at -0.40005 0)
			(size 0 0)
			(layers "B.Cu" "B.Mask" "B.Paste")
			(net "GND")
		)
	)
	(footprint ""
		(layer "B.Cu")
		(at 238.633 -340.741 180)
		(property "Reference" "R808"
			(at 0 0 0)
			(layer "B.SilkS")
			(hide yes)
			(effects
				(font
					(size 1.27 1.27)
				)
				(justify mirror)
			)
		)
		(property "Value" ""
			(at 0 0 0)
			(layer "B.Fab")
			(effects
				(font
					(size 1.27 1.27)
				)
				(justify mirror)
			)
		)
		(duplicate_pad_numbers_are_jumpers no)
		(fp_line
			(start 0.32512 0.175006)
			(end 0.32512 -0.175006)
			(stroke
				(width 0.1)
				(type default)
			)
			(layer "B.Fab")
		)
		(fp_line
			(start 0.32512 -0.175006)
			(end -0.32512 -0.175006)
			(stroke
				(width 0.1)
				(type default)
			)
			(layer "B.Fab")
		)
		(fp_line
			(start -0.32512 0.175006)
			(end 0.32512 0.175006)
			(stroke
				(width 0.1)
				(type default)
			)
			(layer "B.Fab")
		)
		(fp_line
			(start -0.32512 -0.175006)
			(end -0.32512 0.175006)
			(stroke
				(width 0.1)
				(type default)
			)
			(layer "B.Fab")
		)
		(pad "1" smd rect
			(at 0.2667 0)
			(size 0.3048 0.381)
			(layers "B.Cu" "B.Mask" "B.Paste")
			(net "SMB_RT_CPU1_P2_ROM_MUX_2D_SDA")
		)
		(pad "2" smd rect
			(at -0.2667 0 180)
			(size 0.3048 0.381)
			(layers "B.Cu" "B.Mask" "B.Paste")
			(net "SMB_RT_CPU1_P2_ROM_MUX_2D_R_SDA")
		)
	)
	(footprint ""
		(layer "B.Cu")
		(at 384.240278 -137.535158 90)
		(property "Reference" "PC471"
			(at 0 0 90)
			(layer "B.SilkS")
			(hide yes)
			(effects
				(font
					(size 1.27 1.27)
				)
				(justify mirror)
			)
		)
		(property "Value" ""
			(at 0 0 90)
			(layer "B.Fab")
			(effects
				(font
					(size 1.27 1.27)
				)
				(justify mirror)
			)
		)
		(duplicate_pad_numbers_are_jumpers no)
		(fp_line
			(start 0.7874 -0.4064)
			(end -0.7874 -0.4064)
			(stroke
				(width 0.1524)
				(type default)
			)
			(layer "B.SilkS")
		)
		(fp_line
			(start -0.7874 -0.4064)
			(end -0.7874 0.4064)
			(stroke
				(width 0.1524)
				(type default)
			)
			(layer "B.SilkS")
		)
		(fp_line
			(start 0.7874 0.4064)
			(end 0.7874 -0.4064)
			(stroke
				(width 0.1524)
				(type default)
			)
			(layer "B.SilkS")
		)
		(fp_line
			(start -0.7874 0.4064)
			(end 0.7874 0.4064)
			(stroke
				(width 0.1524)
				(type default)
			)
			(layer "B.SilkS")
		)
		(fp_line
			(start 0.67945 -0.305054)
			(end 0.12065 -0.305054)
			(stroke
				(width 0.1)
				(type default)
			)
			(layer "B.Fab")
		)
		(fp_line
			(start 0.12065 -0.305054)
			(end 0.12065 -0.2794)
			(stroke
				(width 0.1)
				(type default)
			)
			(layer "B.Fab")
		)
		(fp_line
			(start -0.12065 -0.3048)
			(end -0.67945 -0.3048)
			(stroke
				(width 0.1)
				(type default)
			)
			(layer "B.Fab")
		)
		(fp_line
			(start -0.67945 -0.3048)
			(end -0.67945 0.3048)
			(stroke
				(width 0.1)
				(type default)
			)
			(layer "B.Fab")
		)
		(fp_line
			(start 0.12065 -0.2794)
			(end -0.12065 -0.2794)
			(stroke
				(width 0.1)
				(type default)
			)
			(layer "B.Fab")
		)
		(fp_line
			(start -0.12065 -0.2794)
			(end -0.12065 -0.3048)
			(stroke
				(width 0.1)
				(type default)
			)
			(layer "B.Fab")
		)
		(fp_line
			(start 0.12065 0.2794)
			(end 0.12065 0.3048)
			(stroke
				(width 0.1)
				(type default)
			)
			(layer "B.Fab")
		)
		(fp_line
			(start -0.120396 0.2794)
			(end 0.12065 0.2794)
			(stroke
				(width 0.1)
				(type default)
			)
			(layer "B.Fab")
		)
		(fp_line
			(start 0.67945 0.3048)
			(end 0.67945 -0.305054)
			(stroke
				(width 0.1)
				(type default)
			)
			(layer "B.Fab")
		)
		(fp_line
			(start 0.12065 0.3048)
			(end 0.67945 0.3048)
			(stroke
				(width 0.1)
				(type default)
			)
			(layer "B.Fab")
		)
		(fp_line
			(start -0.120396 0.3048)
			(end -0.120396 0.2794)
			(stroke
				(width 0.1)
				(type default)
			)
			(layer "B.Fab")
		)
		(fp_line
			(start -0.67945 0.3048)
			(end -0.120396 0.3048)
			(stroke
				(width 0.1)
				(type default)
			)
			(layer "B.Fab")
		)
		(pad "1" smd circle
			(at 0.40005 0 270)
			(size 0 0)
			(layers "B.Cu" "B.Mask" "B.Paste")
			(net "PVDDCR_CPU0_P0_VCC")
		)
		(pad "2" smd circle
			(at -0.40005 0 270)
			(size 0 0)
			(layers "B.Cu" "B.Mask" "B.Paste")
			(net "GND")
		)
	)
)
